(kicad_pcb
	(version 20260206)
	(generator "pcbnew")
	(generator_version "10.0")
	(general
		(thickness 1.6)
		(legacy_teardrops no)
	)
	(paper "A4")
	(title_block
		(title "04192023_DAF0TMB3IC0_F0TG_MB_C_brd_V02_OCP.brd")
		(comment 1 "Grand Teton / footprint 2417 of 8354 (U6015), pads 337-354 of 354")
	)
	(layers
		(0 "F.Cu" signal "TOP")
		(4 "In1.Cu" signal "GND")
		(6 "In2.Cu" signal "IN1")
		(8 "In3.Cu" signal "GND1")
		(10 "In4.Cu" signal "IN2")
		(12 "In5.Cu" signal "GND2")
		(14 "In6.Cu" signal "IN3")
		(16 "In7.Cu" signal "GND3")
		(18 "In8.Cu" signal "VCC")
		(20 "In9.Cu" signal "VCC1")
		(22 "In10.Cu" signal "GND4")
		(24 "In11.Cu" signal "IN4")
		(26 "In12.Cu" signal "GND5")
		(28 "In13.Cu" signal "IN5")
		(30 "In14.Cu" signal "GND6")
		(32 "In15.Cu" signal "IN6")
		(34 "In16.Cu" signal "GND7")
		(2 "B.Cu" signal "BOTTOM")
		(9 "F.Adhes" user "F.Adhesive")
		(11 "B.Adhes" user "B.Adhesive")
		(13 "F.Paste" user "Package Geometry/Pastemask Top")
		(15 "B.Paste" user "Package Geometry/Pastemask Bottom")
		(5 "F.SilkS" user "Ref Des/Silkscreen Top")
		(7 "B.SilkS" user "Ref Des/Silkscreen Bottom")
		(1 "F.Mask" user "Board Geometry/Soldermask Top")
		(3 "B.Mask" user "Board Geometry/Soldermask Bottom")
		(17 "Dwgs.User" user "User.Drawings")
		(19 "Cmts.User" user "User.Comments")
		(21 "Eco1.User" user "User.Eco1")
		(23 "Eco2.User" user "User.Eco2")
		(25 "Edge.Cuts" user "Board Geometry/Outline")
		(27 "Margin" user)
		(31 "F.CrtYd" user "Package Geometry/Place Bound Top")
		(29 "B.CrtYd" user "Package Geometry/Place Bound Bottom")
		(35 "F.Fab" user "Ref Des/Assembly Top")
		(33 "B.Fab" user "Ref Des/Assembly Bottom")
	)
	(footprint ""
		(layer "F.Cu")
		(at 88.995758 -387.342634)
		(property "Reference" "U6015"
			(at -7.723124 -7.528052 0)
			(unlocked yes)
			(layer "F.SilkS")
			(effects
				(font
					(size 0.7874 0.5842)
					(thickness 0.1524)
				)
				(justify left)
			)
		)
		(property "Value" ""
			(at 0 0 0)
			(layer "F.Fab")
			(effects
				(font
					(size 1.27 1.27)
				)
			)
		)
		(duplicate_pad_numbers_are_jumpers no)
		(pad "P10" smd circle
			(at 8.802624 -1.431798)
			(size 0.381 0.381)
			(layers "F.Cu" "F.Mask" "F.Paste")
			(net "P5E_CPU1_P1_TX_BUF_DN<15>")
		)
		(pad "P29" smd circle
			(at 8.802624 2.032254)
			(size 0.381 0.381)
			(layers "F.Cu" "F.Mask" "F.Paste")
			(net "P5E_CPU1_P1_RX_DN<15>")
		)
		(pad "R1" smd oval
			(at 8.64997 -3.938524)
			(size 0.254 0.3302)
			(layers "F.Cu" "F.Mask" "F.Paste")
			(net "P5E_CPU1_P1_RX_BUF_DP<15>")
		)
		(pad "R35" smd oval
			(at 8.64997 3.940048)
			(size 0.254 0.3302)
			(layers "F.Cu" "F.Mask" "F.Paste")
			(net "P5E_CPU1_P1_TX_C_DP<15>")
		)
		(pad "T4" smd circle
			(at 8.402574 -2.817368)
			(size 0.381 0.381)
			(layers "F.Cu" "F.Mask" "F.Paste")
			(net "GND")
		)
		(pad "T13" smd circle
			(at 8.402574 -0.79629)
			(size 0.3048 0.3048)
			(layers "F.Cu" "F.Mask" "F.Paste")
			(net "GND")
		)
		(pad "T17" smd circle
			(at 8.402574 -0.296164)
			(size 0.3048 0.3048)
			(layers "F.Cu" "F.Mask" "F.Paste")
			(net "P0V9_CPU1_RT1_2A")
		)
		(pad "T20" smd circle
			(at 8.402574 0.203708)
			(size 0.3048 0.3048)
			(layers "F.Cu" "F.Mask" "F.Paste")
			(net "P0V9_CPU1_RT1_2A")
		)
		(pad "T22" smd circle
			(at 8.402574 0.703834)
			(size 0.3048 0.3048)
			(layers "F.Cu" "F.Mask" "F.Paste")
			(net "GND")
		)
		(pad "T32" smd circle
			(at 8.402574 2.724912)
			(size 0.381 0.381)
			(layers "F.Cu" "F.Mask" "F.Paste")
			(net "GND")
		)
		(pad "U2" smd circle
			(at 8.349996 -3.41884)
			(size 0.3048 0.3048)
			(layers "F.Cu" "F.Mask" "F.Paste")
			(net "GND")
		)
		(pad "U34" smd circle
			(at 8.349996 3.420364)
			(size 0.3048 0.3048)
			(layers "F.Cu" "F.Mask" "F.Paste")
			(net "GND")
		)
		(pad "V1" smd oval
			(at 8.050022 -3.938524)
			(size 0.254 0.3302)
			(layers "F.Cu" "F.Mask" "F.Paste")
			(net "GND")
		)
		(pad "V35" smd oval
			(at 8.050022 3.940048)
			(size 0.254 0.3302)
			(layers "F.Cu" "F.Mask" "F.Paste")
			(net "GND")
		)
		(pad "W7" smd circle
			(at 8.002524 -2.12471)
			(size 0.381 0.381)
			(layers "F.Cu" "F.Mask" "F.Paste")
			(net "P5E_CPU1_P1_TX_BUF_DP<14>")
		)
		(pad "W26" smd circle
			(at 8.002524 1.339342)
			(size 0.381 0.381)
			(layers "F.Cu" "F.Mask" "F.Paste")
			(net "P5E_CPU1_P1_RX_DP<14>")
		)
		(pad "Y2" smd circle
			(at 7.750048 -3.41884)
			(size 0.3048 0.3048)
			(layers "F.Cu" "F.Mask" "F.Paste")
			(net "P5E_CPU1_P1_RX_BUF_DN<14>")
		)
		(pad "Y34" smd circle
			(at 7.750048 3.420364)
			(size 0.3048 0.3048)
			(layers "F.Cu" "F.Mask" "F.Paste")
			(net "P5E_CPU1_P1_TX_C_DP<14>")
		)
	)
)
